(kicad_pcb
	(version 20260206)
	(generator "pcbnew")
	(generator_version "10.0")
	(general
		(thickness 1.6)
		(legacy_teardrops no)
	)
	(paper "A4")
	(title_block
		(title "04192023_DAF0TMB3IC0_F0TG_MB_C_brd_V02_OCP.brd")
		(comment 1 "Grand Teton / footprints 2624-2630 of 8354")
	)
	(layers
		(0 "F.Cu" signal "TOP")
		(4 "In1.Cu" signal "GND")
		(6 "In2.Cu" signal "IN1")
		(8 "In3.Cu" signal "GND1")
		(10 "In4.Cu" signal "IN2")
		(12 "In5.Cu" signal "GND2")
		(14 "In6.Cu" signal "IN3")
		(16 "In7.Cu" signal "GND3")
		(18 "In8.Cu" signal "VCC")
		(20 "In9.Cu" signal "VCC1")
		(22 "In10.Cu" signal "GND4")
		(24 "In11.Cu" signal "IN4")
		(26 "In12.Cu" signal "GND5")
		(28 "In13.Cu" signal "IN5")
		(30 "In14.Cu" signal "GND6")
		(32 "In15.Cu" signal "IN6")
		(34 "In16.Cu" signal "GND7")
		(2 "B.Cu" signal "BOTTOM")
		(9 "F.Adhes" user "F.Adhesive")
		(11 "B.Adhes" user "B.Adhesive")
		(13 "F.Paste" user "Package Geometry/Pastemask Top")
		(15 "B.Paste" user "Package Geometry/Pastemask Bottom")
		(5 "F.SilkS" user "Ref Des/Silkscreen Top")
		(7 "B.SilkS" user "Ref Des/Silkscreen Bottom")
		(1 "F.Mask" user "Board Geometry/Soldermask Top")
		(3 "B.Mask" user "Board Geometry/Soldermask Bottom")
		(17 "Dwgs.User" user "User.Drawings")
		(19 "Cmts.User" user "User.Comments")
		(21 "Eco1.User" user "User.Eco1")
		(23 "Eco2.User" user "User.Eco2")
		(25 "Edge.Cuts" user "Board Geometry/Outline")
		(27 "Margin" user)
		(31 "F.CrtYd" user "Package Geometry/Place Bound Top")
		(29 "B.CrtYd" user "Package Geometry/Place Bound Bottom")
		(35 "F.Fab" user "Ref Des/Assembly Top")
		(33 "B.Fab" user "Ref Des/Assembly Bottom")
	)
	(footprint ""
		(layer "F.Cu")
		(at 271.085056 -114.21237)
		(property "Reference" "R3722"
			(at 0 0 0)
			(layer "F.SilkS")
			(hide yes)
			(effects
				(font
					(size 1.27 1.27)
				)
			)
		)
		(property "Value" ""
			(at 0 0 0)
			(layer "F.Fab")
			(effects
				(font
					(size 1.27 1.27)
				)
			)
		)
		(duplicate_pad_numbers_are_jumpers no)
		(fp_line
			(start -0.7874 -0.4064)
			(end 0.7874 -0.4064)
			(stroke
				(width 0.1524)
				(type default)
			)
			(layer "F.SilkS")
		)
		(fp_line
			(start -0.7874 0.4064)
			(end -0.7874 -0.4064)
			(stroke
				(width 0.1524)
				(type default)
			)
			(layer "F.SilkS")
		)
		(fp_line
			(start 0.7874 -0.4064)
			(end 0.7874 0.4064)
			(stroke
				(width 0.1524)
				(type default)
			)
			(layer "F.SilkS")
		)
		(fp_line
			(start 0.7874 0.4064)
			(end -0.7874 0.4064)
			(stroke
				(width 0.1524)
				(type default)
			)
			(layer "F.SilkS")
		)
		(fp_line
			(start -0.67945 -0.305054)
			(end -0.12065 -0.305054)
			(stroke
				(width 0.1)
				(type default)
			)
			(layer "F.Fab")
		)
		(fp_line
			(start -0.67945 0.3048)
			(end -0.67945 -0.305054)
			(stroke
				(width 0.1)
				(type default)
			)
			(layer "F.Fab")
		)
		(fp_line
			(start -0.12065 -0.305054)
			(end -0.12065 -0.2794)
			(stroke
				(width 0.1)
				(type default)
			)
			(layer "F.Fab")
		)
		(fp_line
			(start -0.12065 -0.2794)
			(end 0.12065 -0.2794)
			(stroke
				(width 0.1)
				(type default)
			)
			(layer "F.Fab")
		)
		(fp_line
			(start -0.12065 0.2794)
			(end -0.12065 0.3048)
			(stroke
				(width 0.1)
				(type default)
			)
			(layer "F.Fab")
		)
		(fp_line
			(start -0.12065 0.3048)
			(end -0.67945 0.3048)
			(stroke
				(width 0.1)
				(type default)
			)
			(layer "F.Fab")
		)
		(fp_line
			(start 0.120396 0.2794)
			(end -0.12065 0.2794)
			(stroke
				(width 0.1)
				(type default)
			)
			(layer "F.Fab")
		)
		(fp_line
			(start 0.120396 0.3048)
			(end 0.120396 0.2794)
			(stroke
				(width 0.1)
				(type default)
			)
			(layer "F.Fab")
		)
		(fp_line
			(start 0.12065 -0.3048)
			(end 0.67945 -0.3048)
			(stroke
				(width 0.1)
				(type default)
			)
			(layer "F.Fab")
		)
		(fp_line
			(start 0.12065 -0.2794)
			(end 0.12065 -0.3048)
			(stroke
				(width 0.1)
				(type default)
			)
			(layer "F.Fab")
		)
		(fp_line
			(start 0.67945 -0.3048)
			(end 0.67945 0.3048)
			(stroke
				(width 0.1)
				(type default)
			)
			(layer "F.Fab")
		)
		(fp_line
			(start 0.67945 0.3048)
			(end 0.120396 0.3048)
			(stroke
				(width 0.1)
				(type default)
			)
			(layer "F.Fab")
		)
		(pad "1" smd circle
			(at -0.40005 0)
			(size 0 0)
			(layers "F.Cu" "F.Mask" "F.Paste")
			(net "SMB_LM75_3_3V3AUX_SDA_R")
		)
		(pad "2" smd circle
			(at 0.40005 0)
			(size 0 0)
			(layers "F.Cu" "F.Mask" "F.Paste")
			(net "SMB_LM75_3_3V3AUX_SDA")
		)
	)
	(footprint ""
		(layer "F.Cu")
		(at 439.471308 -405.788622 -90)
		(property "Reference" "PR6550"
			(at 0 0 270)
			(layer "F.SilkS")
			(hide yes)
			(effects
				(font
					(size 1.27 1.27)
				)
			)
		)
		(property "Value" ""
			(at 0 0 270)
			(layer "F.Fab")
			(effects
				(font
					(size 1.27 1.27)
				)
			)
		)
		(duplicate_pad_numbers_are_jumpers no)
		(fp_line
			(start -0.7874 0.4064)
			(end -0.7874 -0.4064)
			(stroke
				(width 0.1524)
				(type default)
			)
			(layer "F.SilkS")
		)
		(fp_line
			(start 0.7874 0.4064)
			(end -0.7874 0.4064)
			(stroke
				(width 0.1524)
				(type default)
			)
			(layer "F.SilkS")
		)
		(fp_line
			(start -0.7874 -0.4064)
			(end 0.7874 -0.4064)
			(stroke
				(width 0.1524)
				(type default)
			)
			(layer "F.SilkS")
		)
		(fp_line
			(start 0.7874 -0.4064)
			(end 0.7874 0.4064)
			(stroke
				(width 0.1524)
				(type default)
			)
			(layer "F.SilkS")
		)
		(fp_line
			(start -0.67945 0.3048)
			(end -0.67945 -0.305054)
			(stroke
				(width 0.1)
				(type default)
			)
			(layer "F.Fab")
		)
		(fp_line
			(start -0.12065 0.3048)
			(end -0.67945 0.3048)
			(stroke
				(width 0.1)
				(type default)
			)
			(layer "F.Fab")
		)
		(fp_line
			(start 0.120396 0.3048)
			(end 0.120396 0.2794)
			(stroke
				(width 0.1)
				(type default)
			)
			(layer "F.Fab")
		)
		(fp_line
			(start 0.67945 0.3048)
			(end 0.120396 0.3048)
			(stroke
				(width 0.1)
				(type default)
			)
			(layer "F.Fab")
		)
		(fp_line
			(start -0.12065 0.2794)
			(end -0.12065 0.3048)
			(stroke
				(width 0.1)
				(type default)
			)
			(layer "F.Fab")
		)
		(fp_line
			(start 0.120396 0.2794)
			(end -0.12065 0.2794)
			(stroke
				(width 0.1)
				(type default)
			)
			(layer "F.Fab")
		)
		(fp_line
			(start -0.12065 -0.2794)
			(end 0.12065 -0.2794)
			(stroke
				(width 0.1)
				(type default)
			)
			(layer "F.Fab")
		)
		(fp_line
			(start 0.12065 -0.2794)
			(end 0.12065 -0.3048)
			(stroke
				(width 0.1)
				(type default)
			)
			(layer "F.Fab")
		)
		(fp_line
			(start 0.12065 -0.3048)
			(end 0.67945 -0.3048)
			(stroke
				(width 0.1)
				(type default)
			)
			(layer "F.Fab")
		)
		(fp_line
			(start 0.67945 -0.3048)
			(end 0.67945 0.3048)
			(stroke
				(width 0.1)
				(type default)
			)
			(layer "F.Fab")
		)
		(fp_line
			(start -0.67945 -0.305054)
			(end -0.12065 -0.305054)
			(stroke
				(width 0.1)
				(type default)
			)
			(layer "F.Fab")
		)
		(fp_line
			(start -0.12065 -0.305054)
			(end -0.12065 -0.2794)
			(stroke
				(width 0.1)
				(type default)
			)
			(layer "F.Fab")
		)
		(pad "1" smd circle
			(at -0.40005 0 270)
			(size 0 0)
			(layers "F.Cu" "F.Mask" "F.Paste")
			(net "P5V_AUX")
		)
		(pad "2" smd circle
			(at 0.40005 0 270)
			(size 0 0)
			(layers "F.Cu" "F.Mask" "F.Paste")
			(net "P0V9_RETIMER_CPU0_PVCC")
		)
	)
	(footprint ""
		(layer "F.Cu")
		(at 457.687426 -103.646224)
		(property "Reference" "U8"
			(at -2.8321 -1.679448 0)
			(unlocked yes)
			(layer "F.SilkS")
			(effects
				(font
					(size 0.7874 0.5842)
					(thickness 0.1524)
				)
				(justify left)
			)
		)
		(property "Value" ""
			(at 0 0 0)
			(layer "F.Fab")
			(effects
				(font
					(size 1.27 1.27)
				)
			)
		)
		(duplicate_pad_numbers_are_jumpers no)
		(fp_line
			(start -1.38176 -1.100074)
			(end -1.38176 1.100074)
			(stroke
				(width 0.1524)
				(type default)
			)
			(layer "F.SilkS")
		)
		(fp_line
			(start -1.38176 1.100074)
			(end 1.38176 1.100074)
			(stroke
				(width 0.1524)
				(type default)
			)
			(layer "F.SilkS")
		)
		(fp_line
			(start -0.592074 -1.100074)
			(end -1.38176 -1.100074)
			(stroke
				(width 0.1524)
				(type default)
			)
			(layer "F.SilkS")
		)
		(fp_line
			(start 0 -0.508)
			(end -0.592074 -1.100074)
			(stroke
				(width 0.1524)
				(type default)
			)
			(layer "F.SilkS")
		)
		(fp_line
			(start 0.592074 -1.100074)
			(end 0 -0.508)
			(stroke
				(width 0.1524)
				(type default)
			)
			(layer "F.SilkS")
		)
		(fp_line
			(start 1.38176 -1.100074)
			(end 0.592074 -1.100074)
			(stroke
				(width 0.1524)
				(type default)
			)
			(layer "F.SilkS")
		)
		(fp_line
			(start 1.38176 1.100074)
			(end 1.38176 -1.100074)
			(stroke
				(width 0.1524)
				(type default)
			)
			(layer "F.SilkS")
		)
		(fp_poly
			(pts
				(xy -1.9431 -0.429768) (xy -1.9431 -0.870204) (xy -1.50241 -0.649986)
			)
			(stroke
				(width 0)
				(type default)
			)
			(fill yes)
			(layer "F.SilkS")
		)
		(fp_line
			(start -0.674878 -1.100074)
			(end -0.674878 1.100074)
			(stroke
				(width 0.1)
				(type default)
			)
			(layer "F.Fab")
		)
		(fp_line
			(start -0.674878 1.100074)
			(end 0.674878 1.100074)
			(stroke
				(width 0.1)
				(type default)
			)
			(layer "F.Fab")
		)
		(fp_line
			(start 0.674878 -1.100074)
			(end -0.674878 -1.100074)
			(stroke
				(width 0.1)
				(type default)
			)
			(layer "F.Fab")
		)
		(fp_line
			(start 0.674878 1.100074)
			(end 0.674878 -1.100074)
			(stroke
				(width 0.1)
				(type default)
			)
			(layer "F.Fab")
		)
		(fp_poly
			(pts
				(xy -1.9431 -0.870204) (xy -1.50241 -0.649986) (xy -1.9431 -0.429768)
			)
			(stroke
				(width 0)
				(type default)
			)
			(fill yes)
			(layer "F.Fab")
		)
		(pad "1" smd rect
			(at -0.94996 -0.649986 270)
			(size 0.4318 0.6096)
			(layers "F.Cu" "F.Mask" "F.Paste")
			(net "OCP_SFF_PRSNT2_R_N")
		)
		(pad "2" smd rect
			(at -0.94996 0 270)
			(size 0.4318 0.6096)
			(layers "F.Cu" "F.Mask" "F.Paste")
			(net "GND")
		)
		(pad "3" smd rect
			(at -0.94996 0.649986 270)
			(size 0.4318 0.6096)
			(layers "F.Cu" "F.Mask" "F.Paste")
			(net "OCP_SFF_PRSNT3_R_N")
		)
		(pad "4" smd rect
			(at 0.94996 0.649986 270)
			(size 0.4318 0.6096)
			(layers "F.Cu" "F.Mask" "F.Paste")
			(net "HP_LVC3_OCP_V3_1_PRSNT2_N_R")
		)
		(pad "5" smd rect
			(at 0.94996 0 270)
			(size 0.4318 0.6096)
			(layers "F.Cu" "F.Mask" "F.Paste")
			(net "P3V3_AUX")
		)
		(pad "6" smd rect
			(at 0.94996 -0.649986 270)
			(size 0.4318 0.6096)
			(layers "F.Cu" "F.Mask" "F.Paste")
			(net "HP_LVC3_OCP_V3_1_PRSNT2_N_R")
		)
	)
	(footprint ""
		(layer "F.Cu")
		(at 169.799 -132.08)
		(property "Reference" "U100"
			(at -5.050536 -1.718564 0)
			(unlocked yes)
			(layer "F.SilkS")
			(effects
				(font
					(size 0.7874 0.5842)
					(thickness 0.1524)
				)
				(justify left)
			)
		)
		(property "Value" ""
			(at 0 0 0)
			(layer "F.Fab")
			(effects
				(font
					(size 1.27 1.27)
				)
			)
		)
		(duplicate_pad_numbers_are_jumpers no)
		(fp_line
			(start -1.934972 -1.5494)
			(end 1.934972 -1.5494)
			(stroke
				(width 0.1524)
				(type default)
			)
			(layer "F.SilkS")
		)
		(fp_line
			(start -1.934972 1.5494)
			(end -1.934972 -1.5494)
			(stroke
				(width 0.1524)
				(type default)
			)
			(layer "F.SilkS")
		)
		(fp_line
			(start 1.934972 -1.5494)
			(end 1.934972 1.5494)
			(stroke
				(width 0.1524)
				(type default)
			)
			(layer "F.SilkS")
		)
		(fp_line
			(start 1.934972 1.5494)
			(end -1.934972 1.5494)
			(stroke
				(width 0.1524)
				(type default)
			)
			(layer "F.SilkS")
		)
		(fp_line
			(start -0.901446 -1.5494)
			(end 0.901446 -1.5494)
			(stroke
				(width 0.1)
				(type default)
			)
			(layer "F.Fab")
		)
		(fp_line
			(start -0.901446 1.5494)
			(end -0.901446 -1.5494)
			(stroke
				(width 0.1)
				(type default)
			)
			(layer "F.Fab")
		)
		(fp_line
			(start 0.901446 -1.5494)
			(end 0.901446 1.5494)
			(stroke
				(width 0.1)
				(type default)
			)
			(layer "F.Fab")
		)
		(fp_line
			(start 0.901446 1.5494)
			(end -0.901446 1.5494)
			(stroke
				(width 0.1)
				(type default)
			)
			(layer "F.Fab")
		)
		(pad "1" smd rect
			(at -1.299972 -0.94996 270)
			(size 0.8128 1.016)
			(layers "F.Cu" "F.Mask" "F.Paste")
			(net "PWRGD_P5V_R")
		)
		(pad "2" smd rect
			(at -1.299972 0.94996 270)
			(size 0.8128 1.016)
			(layers "F.Cu" "F.Mask" "F.Paste")
			(net "GND")
		)
		(pad "3" smd rect
			(at 1.299972 0 270)
			(size 0.8128 1.016)
			(layers "F.Cu" "F.Mask" "F.Paste")
			(net "P5V")
		)
	)
	(footprint ""
		(layer "F.Cu")
		(at 171.9072 -94.833948 -90)
		(property "Reference" "R6013"
			(at 0 0 270)
			(layer "F.SilkS")
			(hide yes)
			(effects
				(font
					(size 1.27 1.27)
				)
			)
		)
		(property "Value" ""
			(at 0 0 270)
			(layer "F.Fab")
			(effects
				(font
					(size 1.27 1.27)
				)
			)
		)
		(duplicate_pad_numbers_are_jumpers no)
		(fp_line
			(start -0.7874 0.4064)
			(end -0.7874 -0.4064)
			(stroke
				(width 0.1524)
				(type default)
			)
			(layer "F.SilkS")
		)
		(fp_line
			(start 0.7874 0.4064)
			(end -0.7874 0.4064)
			(stroke
				(width 0.1524)
				(type default)
			)
			(layer "F.SilkS")
		)
		(fp_line
			(start -0.7874 -0.4064)
			(end 0.7874 -0.4064)
			(stroke
				(width 0.1524)
				(type default)
			)
			(layer "F.SilkS")
		)
		(fp_line
			(start 0.7874 -0.4064)
			(end 0.7874 0.4064)
			(stroke
				(width 0.1524)
				(type default)
			)
			(layer "F.SilkS")
		)
		(fp_line
			(start -0.67945 0.3048)
			(end -0.67945 -0.305054)
			(stroke
				(width 0.1)
				(type default)
			)
			(layer "F.Fab")
		)
		(fp_line
			(start -0.12065 0.3048)
			(end -0.67945 0.3048)
			(stroke
				(width 0.1)
				(type default)
			)
			(layer "F.Fab")
		)
		(fp_line
			(start 0.120396 0.3048)
			(end 0.120396 0.2794)
			(stroke
				(width 0.1)
				(type default)
			)
			(layer "F.Fab")
		)
		(fp_line
			(start 0.67945 0.3048)
			(end 0.120396 0.3048)
			(stroke
				(width 0.1)
				(type default)
			)
			(layer "F.Fab")
		)
		(fp_line
			(start -0.12065 0.2794)
			(end -0.12065 0.3048)
			(stroke
				(width 0.1)
				(type default)
			)
			(layer "F.Fab")
		)
		(fp_line
			(start 0.120396 0.2794)
			(end -0.12065 0.2794)
			(stroke
				(width 0.1)
				(type default)
			)
			(layer "F.Fab")
		)
		(fp_line
			(start -0.12065 -0.2794)
			(end 0.12065 -0.2794)
			(stroke
				(width 0.1)
				(type default)
			)
			(layer "F.Fab")
		)
		(fp_line
			(start 0.12065 -0.2794)
			(end 0.12065 -0.3048)
			(stroke
				(width 0.1)
				(type default)
			)
			(layer "F.Fab")
		)
		(fp_line
			(start 0.12065 -0.3048)
			(end 0.67945 -0.3048)
			(stroke
				(width 0.1)
				(type default)
			)
			(layer "F.Fab")
		)
		(fp_line
			(start 0.67945 -0.3048)
			(end 0.67945 0.3048)
			(stroke
				(width 0.1)
				(type default)
			)
			(layer "F.Fab")
		)
		(fp_line
			(start -0.67945 -0.305054)
			(end -0.12065 -0.305054)
			(stroke
				(width 0.1)
				(type default)
			)
			(layer "F.Fab")
		)
		(fp_line
			(start -0.12065 -0.305054)
			(end -0.12065 -0.2794)
			(stroke
				(width 0.1)
				(type default)
			)
			(layer "F.Fab")
		)
		(pad "1" smd circle
			(at -0.40005 0 270)
			(size 0 0)
			(layers "F.Cu" "F.Mask" "F.Paste")
			(net "SGPIO_SCM_CLK_<1>")
		)
		(pad "2" smd circle
			(at 0.40005 0 270)
			(size 0 0)
			(layers "F.Cu" "F.Mask" "F.Paste")
			(net "SGPIO_SCM_CLK_R_<1>")
		)
	)
	(footprint ""
		(layer "F.Cu")
		(at 138.067542 -382.6764 180)
		(property "Reference" "R927"
			(at 0 0 180)
			(layer "F.SilkS")
			(hide yes)
			(effects
				(font
					(size 1.27 1.27)
				)
			)
		)
		(property "Value" ""
			(at 0 0 180)
			(layer "F.Fab")
			(effects
				(font
					(size 1.27 1.27)
				)
			)
		)
		(duplicate_pad_numbers_are_jumpers no)
		(fp_line
			(start 0.32512 0.175006)
			(end -0.32512 0.175006)
			(stroke
				(width 0.1)
				(type default)
			)
			(layer "F.Fab")
		)
		(fp_line
			(start 0.32512 -0.175006)
			(end 0.32512 0.175006)
			(stroke
				(width 0.1)
				(type default)
			)
			(layer "F.Fab")
		)
		(fp_line
			(start -0.32512 0.175006)
			(end -0.32512 -0.175006)
			(stroke
				(width 0.1)
				(type default)
			)
			(layer "F.Fab")
		)
		(fp_line
			(start -0.32512 -0.175006)
			(end 0.32512 -0.175006)
			(stroke
				(width 0.1)
				(type default)
			)
			(layer "F.Fab")
		)
		(pad "1" smd rect
			(at -0.2667 0 180)
			(size 0.3048 0.381)
			(layers "F.Cu" "F.Mask" "F.Paste")
			(net "P1V8_CPU1_RT_1D")
		)
		(pad "2" smd rect
			(at 0.2667 0)
			(size 0.3048 0.381)
			(layers "F.Cu" "F.Mask" "F.Paste")
			(net "RT_CPU1_P3_ADDR1")
		)
	)
	(footprint ""
		(layer "F.Cu")
		(at 192.47358 -413.964882 90)
		(property "Reference" "R2940"
			(at 0 0 90)
			(layer "F.SilkS")
			(hide yes)
			(effects
				(font
					(size 1.27 1.27)
				)
			)
		)
		(property "Value" ""
			(at 0 0 90)
			(layer "F.Fab")
			(effects
				(font
					(size 1.27 1.27)
				)
			)
		)
		(duplicate_pad_numbers_are_jumpers no)
		(fp_line
			(start 0.7874 -0.4064)
			(end 0.7874 0.4064)
			(stroke
				(width 0.1524)
				(type default)
			)
			(layer "F.SilkS")
		)
		(fp_line
			(start -0.7874 -0.4064)
			(end 0.7874 -0.4064)
			(stroke
				(width 0.1524)
				(type default)
			)
			(layer "F.SilkS")
		)
		(fp_line
			(start 0.7874 0.4064)
			(end -0.7874 0.4064)
			(stroke
				(width 0.1524)
				(type default)
			)
			(layer "F.SilkS")
		)
		(fp_line
			(start -0.7874 0.4064)
			(end -0.7874 -0.4064)
			(stroke
				(width 0.1524)
				(type default)
			)
			(layer "F.SilkS")
		)
		(fp_line
			(start -0.12065 -0.305054)
			(end -0.12065 -0.2794)
			(stroke
				(width 0.1)
				(type default)
			)
			(layer "F.Fab")
		)
		(fp_line
			(start -0.67945 -0.305054)
			(end -0.12065 -0.305054)
			(stroke
				(width 0.1)
				(type default)
			)
			(layer "F.Fab")
		)
		(fp_line
			(start 0.67945 -0.3048)
			(end 0.67945 0.3048)
			(stroke
				(width 0.1)
				(type default)
			)
			(layer "F.Fab")
		)
		(fp_line
			(start 0.12065 -0.3048)
			(end 0.67945 -0.3048)
			(stroke
				(width 0.1)
				(type default)
			)
			(layer "F.Fab")
		)
		(fp_line
			(start 0.12065 -0.2794)
			(end 0.12065 -0.3048)
			(stroke
				(width 0.1)
				(type default)
			)
			(layer "F.Fab")
		)
		(fp_line
			(start -0.12065 -0.2794)
			(end 0.12065 -0.2794)
			(stroke
				(width 0.1)
				(type default)
			)
			(layer "F.Fab")
		)
		(fp_line
			(start 0.120396 0.2794)
			(end -0.12065 0.2794)
			(stroke
				(width 0.1)
				(type default)
			)
			(layer "F.Fab")
		)
		(fp_line
			(start -0.12065 0.2794)
			(end -0.12065 0.3048)
			(stroke
				(width 0.1)
				(type default)
			)
			(layer "F.Fab")
		)
		(fp_line
			(start 0.67945 0.3048)
			(end 0.120396 0.3048)
			(stroke
				(width 0.1)
				(type default)
			)
			(layer "F.Fab")
		)
		(fp_line
			(start 0.120396 0.3048)
			(end 0.120396 0.2794)
			(stroke
				(width 0.1)
				(type default)
			)
			(layer "F.Fab")
		)
		(fp_line
			(start -0.12065 0.3048)
			(end -0.67945 0.3048)
			(stroke
				(width 0.1)
				(type default)
			)
			(layer "F.Fab")
		)
		(fp_line
			(start -0.67945 0.3048)
			(end -0.67945 -0.305054)
			(stroke
				(width 0.1)
				(type default)
			)
			(layer "F.Fab")
		)
		(pad "1" smd circle
			(at -0.40005 0 90)
			(size 0 0)
			(layers "F.Cu" "F.Mask" "F.Paste")
			(net "P3V3_AUX")
		)
		(pad "2" smd circle
			(at 0.40005 0 90)
			(size 0 0)
			(layers "F.Cu" "F.Mask" "F.Paste")
			(net "FM_GPU_HSC_EN")
		)
	)
)
